FILE_TYPE = MACRO_DRAWING;
SET COLOR_WIRE YELLOW;
SET COLOR_PROP MONO;
SET COLOR_DOT WHITE;
SET COLOR_ARC YELLOW;
SET COLOR_BODY GREEN;
SET COLOR_NOTE MONO;
SET PROP_DISPLAY VALUE;
SET PAGE_NUMBER P142;
FORCEADD TTL1G126_A..1
R 6
(-3525 2275);
FORCEPROP 1 LAST POWER_GROUP VCC=P3V3_STBY;GND=GND;
J 0
(-3625 2040);
DISPLAY 0.617021 (-3625 2040);
PAINT ORANGE (-3625 2040);
FORCEPROP 1 LASTPIN (-3675 2275) $PN 2
J 2
(-3650 2265);
DISPLAY 0.617021 (-3650 2265);
PAINT WHITE (-3650 2265);
FORCEPROP 1 LAST LOCATION U8E4
J 0
(-3650 2454);
DISPLAY 0.617021 (-3650 2454);
PAINT AQUA (-3650 2454);
FORCEPROP 1 LAST MATERIAL IC
J 0
(-3625 2525);
DISPLAY 0.617021 (-3625 2525);
PAINT SKYBLUE (-3625 2525);
FORCEPROP 1 LASTPIN (-3525 2375) $PN 1
J 0
(-3520 2425);
DISPLAY 0.617021 (-3520 2425);
PAINT WHITE (-3520 2425);
FORCEPROP 1 LASTPIN (-3375 2275) $PN 4
J 0
(-3410 2265);
DISPLAY 0.617021 (-3410 2265);
PAINT WHITE (-3410 2265);
FORCEPROP 1 LAST VALUE 74HC1G126
J 0
(-3575 2125);
DISPLAY 0.617021 (-3575 2125);
PAINT SKYBLUE (-3575 2125);
FORCEPROP 1 LAST PART_NUMBER A79322-001
J 0
(-3425 2365);
DISPLAY 0.617021 (-3425 2365);
PAINT BLUE (-3425 2365);
FORCEPROP 1 LAST PACK_TYPE SOT
J 0
(-3575 2025);
DISPLAY 0.978723 (-3575 2025);
PAINT SKYBLUE (-3575 2025);
DISPLAY INVISIBLE (-3575 2025);
FORCEPROP 2 LAST CDS_LOCATION U8E4
J 0
(-3575 2029);
DISPLAY 0.617021 (-3575 2029);
PAINT AQUA (-3575 2029);
DISPLAY INVISIBLE (-3575 2029);
FORCEPROP 1 LAST PATH I1
J 2
(-3630 2175);
DISPLAY 0.978723 (-3630 2175);
PAINT GREEN (-3630 2175);
DISPLAY INVISIBLE (-3630 2175);
FORCEPROP 2 LAST ROOM PCIE_WAKE_BUFFER
J 0
(-3425 2400);
DISPLAY 1.021277 (-3425 2400);
PAINT ORANGE (-3425 2400);
DISPLAY INVISIBLE (-3425 2400);
FORCEPROP 2 LAST SEC 1
J 0
(-3425 2475);
DISPLAY 0.680851 (-3425 2475);
PAINT MONO (-3425 2475);
DISPLAY INVISIBLE (-3425 2475);
FORCEPROP 2 LAST BOM_COST SB
J 0
(-3425 2450);
DISPLAY 1.021277 (-3425 2450);
PAINT ORANGE (-3425 2450);
DISPLAY INVISIBLE (-3425 2450);
FORCEPROP 2 LAST SEC_TYPE SOT
J 0
(-3425 2475);
DISPLAY 1.021277 (-3425 2475);
PAINT ORANGE (-3425 2475);
DISPLAY INVISIBLE (-3425 2475);
FORCEPROP 2 LAST CDS_LIB mstr_ttl
J 0
(-3525 2275);
PAINT ORANGE (-3525 2275);
DISPLAY INVISIBLE (-3525 2275);
FORCEADD OFFPAGE..1
(-5400 2675);
FORCEPROP 2 LAST $XR0 185 
J 0
(-5652 2675);
DISPLAY 0.638298 (-5652 2675);
PAINT MONO (-5652 2675);
FORCEPROP 2 LAST CDS_LIB mstr_standard
J 0
(-5400 2675);
PAINT ORANGE (-5400 2675);
DISPLAY INVISIBLE (-5400 2675);
FORCEPROP 2 LAST PATH I11
J 0
(-5350 2750);
DISPLAY 1.021277 (-5350 2750);
PAINT ORANGE (-5350 2750);
DISPLAY INVISIBLE (-5350 2750);
FORCEPROP 1 LAST OFFPAGE TRUE
J 0
(-5075 2550);
DISPLAY 0.872340 (-5075 2550);
PAINT GREEN (-5075 2550);
DISPLAY INVISIBLE (-5075 2550);
FORCEPROP 1 LAST COMMENT_BODY TRUE
J 0
(-5275 2575);
DISPLAY 0.872340 (-5275 2575);
PAINT GREEN (-5275 2575);
DISPLAY INVISIBLE (-5275 2575);
FORCEADD OFFPAGE..1
(-5400 2475);
FORCEPROP 2 LAST $XR0 108 
J 0
(-5652 2475);
DISPLAY 0.638298 (-5652 2475);
PAINT MONO (-5652 2475);
FORCEPROP 2 LAST CDS_LIB mstr_standard
J 0
(-5400 2475);
PAINT ORANGE (-5400 2475);
DISPLAY INVISIBLE (-5400 2475);
FORCEPROP 2 LAST PATH I12
J 0
(-5350 2550);
DISPLAY 1.021277 (-5350 2550);
PAINT ORANGE (-5350 2550);
DISPLAY INVISIBLE (-5350 2550);
FORCEPROP 1 LAST OFFPAGE TRUE
J 0
(-5075 2350);
DISPLAY 0.872340 (-5075 2350);
PAINT GREEN (-5075 2350);
DISPLAY INVISIBLE (-5075 2350);
FORCEPROP 1 LAST COMMENT_BODY TRUE
J 0
(-5275 2375);
DISPLAY 0.872340 (-5275 2375);
PAINT GREEN (-5275 2375);
DISPLAY INVISIBLE (-5275 2375);
FORCEADD OFFPAGE..1
(-5400 2275);
FORCEPROP 2 LAST $XR0 186 
J 0
(-5652 2275);
DISPLAY 0.638298 (-5652 2275);
PAINT MONO (-5652 2275);
FORCEPROP 2 LAST CDS_LIB mstr_standard
J 0
(-5400 2275);
PAINT ORANGE (-5400 2275);
DISPLAY INVISIBLE (-5400 2275);
FORCEPROP 2 LAST PATH I13
J 0
(-5350 2350);
DISPLAY 1.021277 (-5350 2350);
PAINT ORANGE (-5350 2350);
DISPLAY INVISIBLE (-5350 2350);
FORCEPROP 1 LAST OFFPAGE TRUE
J 0
(-5075 2150);
DISPLAY 0.872340 (-5075 2150);
PAINT GREEN (-5075 2150);
DISPLAY INVISIBLE (-5075 2150);
FORCEPROP 1 LAST COMMENT_BODY TRUE
J 0
(-5275 2175);
DISPLAY 0.872340 (-5275 2175);
PAINT GREEN (-5275 2175);
DISPLAY INVISIBLE (-5275 2175);
FORCEADD OFFPAGE..1
(-5400 2900);
FORCEPROP 2 LAST $XR0 139 
J 0
(-5652 2900);
DISPLAY 0.638298 (-5652 2900);
PAINT MONO (-5652 2900);
FORCEPROP 2 LAST CDS_LIB mstr_standard
J 0
(-5400 2900);
PAINT ORANGE (-5400 2900);
DISPLAY INVISIBLE (-5400 2900);
FORCEPROP 2 LAST PATH I17
J 0
(-5350 2975);
DISPLAY 1.021277 (-5350 2975);
PAINT ORANGE (-5350 2975);
DISPLAY INVISIBLE (-5350 2975);
FORCEPROP 1 LAST OFFPAGE TRUE
J 0
(-5075 2775);
DISPLAY 0.872340 (-5075 2775);
PAINT GREEN (-5075 2775);
DISPLAY INVISIBLE (-5075 2775);
FORCEPROP 1 LAST COMMENT_BODY TRUE
J 0
(-5275 2800);
DISPLAY 0.872340 (-5275 2800);
PAINT GREEN (-5275 2800);
DISPLAY INVISIBLE (-5275 2800);
FORCEADD RES..1
(-4300 3125);
FORCEPROP 1 LAST WATTAGE 1/16W
J 2
(-4475 3075);
DISPLAY 0.617021 (-4475 3075);
PAINT SKYBLUE (-4475 3075);
FORCEPROP 1 LAST VALUE 0.0
J 2
(-4400 3075);
DISPLAY 0.617021 (-4400 3075);
PAINT SKYBLUE (-4400 3075);
FORCEPROP 1 LASTPIN (-4400 3125) $PN 1
J 0
(-4388 3137);
DISPLAY 0.617021 (-4388 3137);
PAINT ORANGE (-4388 3137);
FORCEPROP 1 LAST TOLERANCE 5%
J 0
(-4350 3075);
DISPLAY 0.617021 (-4350 3075);
PAINT SKYBLUE (-4350 3075);
FORCEPROP 1 LAST LOCATION R8E29
J 0
(-4350 3250);
DISPLAY 0.617021 (-4350 3250);
PAINT AQUA (-4350 3250);
FORCEPROP 1 LASTPIN (-4200 3125) $PN 2
J 0
(-4238 3137);
DISPLAY 0.617021 (-4238 3137);
PAINT ORANGE (-4238 3137);
FORCEPROP 1 LAST PART_NUMBER G21497-005
J 0
(-4200 3025);
DISPLAY 0.617021 (-4200 3025);
PAINT BLUE (-4200 3025);
FORCEPROP 1 LAST MATERIAL EMPTY
J 0
(-4175 3075);
DISPLAY 0.617021 (-4175 3075);
PAINT RED (-4175 3075);
FORCEPROP 1 LAST PACK_TYPE 0402
J 0
(-4025 3075);
DISPLAY 0.617021 (-4025 3075);
PAINT SKYBLUE (-4025 3075);
FORCEPROP 2 LAST CDS_LIB mstr_discrete
J 0
(-4300 3125);
PAINT ORANGE (-4300 3125);
DISPLAY INVISIBLE (-4300 3125);
FORCEPROP 2 LAST CDS_LOCATION R8E29
J 0
(-4350 3175);
DISPLAY 0.617021 (-4350 3175);
PAINT AQUA (-4350 3175);
DISPLAY INVISIBLE (-4350 3175);
FORCEPROP 2 LAST BOM_COST SB
J 0
(-4350 3275);
DISPLAY 1.021277 (-4350 3275);
PAINT ORANGE (-4350 3275);
DISPLAY INVISIBLE (-4350 3275);
FORCEPROP 1 LAST PATH I18
J 0
(-4350 3275);
DISPLAY 0.978723 (-4350 3275);
PAINT WHITE (-4350 3275);
DISPLAY INVISIBLE (-4350 3275);
FORCEPROP 2 LAST ROOM PCIE_WAKE_BUFFER
J 0
(-4350 3225);
DISPLAY 1.021277 (-4350 3225);
PAINT ORANGE (-4350 3225);
DISPLAY INVISIBLE (-4350 3225);
FORCEPROP 2 LAST SEC_TYPE 0402
J 0
(-4350 3325);
DISPLAY 1.021277 (-4350 3325);
PAINT ORANGE (-4350 3325);
DISPLAY INVISIBLE (-4350 3325);
FORCEPROP 2 LAST SEC 1
J 0
(-4350 3325);
PAINT MONO (-4350 3325);
DISPLAY INVISIBLE (-4350 3325);
FORCEADD OFFPAGE..1
(-5400 3125);
FORCEPROP 2 LAST $XR0 146 
J 0
(-5652 3125);
DISPLAY 0.638298 (-5652 3125);
PAINT MONO (-5652 3125);
FORCEPROP 2 LAST CDS_LIB mstr_standard
J 0
(-5400 3125);
PAINT ORANGE (-5400 3125);
DISPLAY INVISIBLE (-5400 3125);
FORCEPROP 2 LAST PATH I19
J 0
(-5350 3200);
DISPLAY 1.021277 (-5350 3200);
PAINT ORANGE (-5350 3200);
DISPLAY INVISIBLE (-5350 3200);
FORCEPROP 1 LAST OFFPAGE TRUE
J 0
(-5075 3000);
DISPLAY 0.872340 (-5075 3000);
PAINT GREEN (-5075 3000);
DISPLAY INVISIBLE (-5075 3000);
FORCEPROP 1 LAST COMMENT_BODY TRUE
J 0
(-5275 3025);
DISPLAY 0.872340 (-5275 3025);
PAINT GREEN (-5275 3025);
DISPLAY INVISIBLE (-5275 3025);
FORCEADD RES..1
(-2625 2275);
FORCEPROP 1 LAST VALUE 33.2
J 2
(-2650 2175);
DISPLAY 0.617021 (-2650 2175);
PAINT SKYBLUE (-2650 2175);
FORCEPROP 1 LAST WATTAGE 1/16W
J 2
(-2650 2125);
DISPLAY 0.617021 (-2650 2125);
PAINT SKYBLUE (-2650 2125);
FORCEPROP 1 LAST TOLERANCE 1%
J 0
(-2625 2175);
DISPLAY 0.617021 (-2625 2175);
PAINT SKYBLUE (-2625 2175);
FORCEPROP 1 LASTPIN (-2725 2275) $PN 1
J 0
(-2713 2287);
DISPLAY 0.617021 (-2713 2287);
PAINT ORANGE (-2713 2287);
FORCEPROP 1 LAST LOCATION R8E17
J 0
(-2675 2325);
DISPLAY 0.617021 (-2675 2325);
PAINT AQUA (-2675 2325);
FORCEPROP 1 LASTPIN (-2525 2275) $PN 2
J 0
(-2563 2287);
DISPLAY 0.617021 (-2563 2287);
PAINT ORANGE (-2563 2287);
FORCEPROP 1 LAST MATERIAL CHIP
J 0
(-2625 2125);
DISPLAY 0.617021 (-2625 2125);
PAINT SKYBLUE (-2625 2125);
FORCEPROP 1 LAST PART_NUMBER G21796-074
J 0
(-2675 2375);
DISPLAY 0.617021 (-2675 2375);
PAINT BLUE (-2675 2375);
FORCEPROP 1 LAST PACK_TYPE 0402
J 0
(-2475 2125);
DISPLAY 0.617021 (-2475 2125);
PAINT SKYBLUE (-2475 2125);
FORCEPROP 2 LAST CDS_LIB mstr_discrete
J 0
(-2625 2275);
PAINT ORANGE (-2625 2275);
DISPLAY INVISIBLE (-2625 2275);
FORCEPROP 2 LAST SEC_TYPE 0402
J 0
(-2675 2475);
DISPLAY 1.021277 (-2675 2475);
PAINT ORANGE (-2675 2475);
DISPLAY INVISIBLE (-2675 2475);
FORCEPROP 2 LAST BOM_COST SB
J 0
(-2675 2475);
DISPLAY 1.021277 (-2675 2475);
PAINT ORANGE (-2675 2475);
DISPLAY INVISIBLE (-2675 2475);
FORCEPROP 2 LAST SEC 1
J 0
(-2675 2475);
PAINT MONO (-2675 2475);
DISPLAY INVISIBLE (-2675 2475);
FORCEPROP 2 LAST CDS_LOCATION R8E17
J 0
(-2675 2325);
DISPLAY 0.617021 (-2675 2325);
PAINT AQUA (-2675 2325);
DISPLAY INVISIBLE (-2675 2325);
FORCEPROP 1 LAST PATH I2
J 0
(-2675 2425);
DISPLAY 0.978723 (-2675 2425);
PAINT WHITE (-2675 2425);
DISPLAY INVISIBLE (-2675 2425);
FORCEPROP 2 LAST ROOM PCIE_WAKE_BUFFER
J 0
(-2675 2425);
DISPLAY 1.021277 (-2675 2425);
PAINT ORANGE (-2675 2425);
DISPLAY INVISIBLE (-2675 2425);
FORCEADD CAP_A..1
(-3500 1550);
FORCEPROP 1 LAST TOLERANCE 10%
J 0
(-3450 1500);
DISPLAY 0.617021 (-3450 1500);
PAINT SKYBLUE (-3450 1500);
FORCEPROP 1 LAST MATERIAL X7R
J 0
(-3450 1450);
DISPLAY 0.617021 (-3450 1450);
PAINT SKYBLUE (-3450 1450);
FORCEPROP 1 LASTPIN (-3500 1450) $PN 2
J 0
(-3490 1430);
DISPLAY 0.617021 (-3490 1430);
PAINT ORANGE (-3490 1430);
FORCEPROP 1 LAST PART_NUMBER A36096-030
J 0
(-3450 1400);
DISPLAY 0.617021 (-3450 1400);
PAINT BLUE (-3450 1400);
FORCEPROP 1 LAST PACK_TYPE 0402V
J 0
(-3450 1350);
DISPLAY 0.617021 (-3450 1350);
PAINT SKYBLUE (-3450 1350);
FORCEPROP 1 LASTPIN (-3500 1650) $PN 1
J 0
(-3490 1630);
DISPLAY 0.617021 (-3490 1630);
PAINT ORANGE (-3490 1630);
FORCEPROP 1 LAST LOCATION C8E5
J 0
(-3450 1650);
DISPLAY 0.617021 (-3450 1650);
PAINT AQUA (-3450 1650);
FORCEPROP 1 LAST VOLTAGE 16V
J 0
(-3450 1550);
DISPLAY 0.617021 (-3450 1550);
PAINT SKYBLUE (-3450 1550);
FORCEPROP 1 LAST VALUE 0.1UF
J 0
(-3450 1600);
DISPLAY 0.617021 (-3450 1600);
PAINT SKYBLUE (-3450 1600);
FORCEPROP 2 LAST CDS_LIB dev_discrete
J 0
(-3500 1550);
PAINT ORANGE (-3500 1550);
DISPLAY INVISIBLE (-3500 1550);
FORCEPROP 2 LAST CDS_SEC 1
J 0
(-3450 1700);
PAINT ORANGE (-3450 1700);
DISPLAY INVISIBLE (-3450 1700);
FORCEPROP 2 LAST CDS_LOCATION C8E5
J 0
(-3450 1650);
DISPLAY 0.617021 (-3450 1650);
PAINT AQUA (-3450 1650);
DISPLAY INVISIBLE (-3450 1650);
FORCEPROP 2 LAST ROOM PCIE_WAKE_BUFFER
J 0
(-3450 1700);
DISPLAY 1.021277 (-3450 1700);
PAINT ORANGE (-3450 1700);
DISPLAY INVISIBLE (-3450 1700);
FORCEPROP 1 LAST PATH I20
J 0
(-3450 1700);
DISPLAY 0.978723 (-3450 1700);
PAINT WHITE (-3450 1700);
DISPLAY INVISIBLE (-3450 1700);
FORCEPROP 2 LAST SEC 1
J 0
(-3450 1750);
PAINT MONO (-3450 1750);
DISPLAY INVISIBLE (-3450 1750);
FORCEPROP 2 LAST SEC_TYPE 0402V
J 0
(-3450 1750);
DISPLAY 1.021277 (-3450 1750);
PAINT ORANGE (-3450 1750);
DISPLAY INVISIBLE (-3450 1750);
FORCEPROP 2 LAST BOM_COST SB
J 0
(-3450 1750);
DISPLAY 1.021277 (-3450 1750);
PAINT ORANGE (-3450 1750);
DISPLAY INVISIBLE (-3450 1750);
FORCEADD P3V3_STBY..1
(-3500 1775);
FORCEPROP 3 LASTPIN (-3500 1725) SIG_NAME P3V3_STBY\g
J 0
(-3490 1735);
DISPLAY 0.659574 (-3490 1735);
PAINT MONO (-3490 1735);
DISPLAY INVISIBLE (-3490 1735);
FORCEPROP 1 LAST VOLTAGE 3.3V
J 0
(-3545 1732);
DISPLAY 0.340426 (-3545 1732);
PAINT SKYBLUE (-3545 1732);
DISPLAY INVISIBLE (-3545 1732);
FORCEPROP 1 LAST PATH I21
J 0
(-3455 1777);
DISPLAY 0.340426 (-3455 1777);
PAINT GREEN (-3455 1777);
DISPLAY INVISIBLE (-3455 1777);
FORCEPROP 2 LAST CDS_LIB mstr_symbols
J 0
(-3500 1775);
PAINT ORANGE (-3500 1775);
DISPLAY INVISIBLE (-3500 1775);
FORCEPROP 1 LAST SIZE 1B
J 0
(-3455 1797);
DISPLAY 0.340426 (-3455 1797);
PAINT GREEN (-3455 1797);
DISPLAY INVISIBLE (-3455 1797);
FORCEPROP 1 LAST BODY_TYPE PLUMBING
J 0
(-3545 1732);
DISPLAY 0.340426 (-3545 1732);
PAINT GREEN (-3545 1732);
DISPLAY INVISIBLE (-3545 1732);
FORCEPROP 1 LAST HDL_POWER P3V3_STBY
J 0
(-3800 1650);
DISPLAY 0.872340 (-3800 1650);
PAINT ORANGE (-3800 1650);
DISPLAY INVISIBLE (-3800 1650);
FORCEADD GND..1
(-3500 1250);
FORCEPROP 3 LASTPIN (-3500 1300) SIG_NAME GND\g
J 0
(-3490 1310);
DISPLAY 0.659574 (-3490 1310);
PAINT MONO (-3490 1310);
DISPLAY INVISIBLE (-3490 1310);
FORCEPROP 1 LAST VOLTAGE 0.0V
J 0
(-3545 1207);
DISPLAY 0.340426 (-3545 1207);
PAINT SKYBLUE (-3545 1207);
DISPLAY INVISIBLE (-3545 1207);
FORCEPROP 1 LAST SIZE 1B
J 0
(-3425 1200);
DISPLAY 0.872340 (-3425 1200);
PAINT AQUA (-3425 1200);
DISPLAY INVISIBLE (-3425 1200);
FORCEPROP 2 LAST CDS_LIB mstr_symbols
J 0
(-3500 1250);
PAINT ORANGE (-3500 1250);
DISPLAY INVISIBLE (-3500 1250);
FORCEPROP 1 LAST PATH I22
J 0
(-3425 1250);
DISPLAY 0.872340 (-3425 1250);
PAINT AQUA (-3425 1250);
DISPLAY INVISIBLE (-3425 1250);
FORCEPROP 1 LAST BODY_TYPE PLUMBING
J 0
(-3545 1207);
DISPLAY 0.340426 (-3545 1207);
PAINT GREEN (-3545 1207);
DISPLAY INVISIBLE (-3545 1207);
FORCEPROP 1 LAST HDL_POWER GND
J 0
(-3500 1400);
DISPLAY 0.872340 (-3500 1400);
PAINT GREEN (-3500 1400);
DISPLAY INVISIBLE (-3500 1400);
FORCEADD RES..2
(-3825 3425);
FORCEPROP 1 LAST PACK_TYPE 0402
J 0
(-3785 3250);
DISPLAY 0.617021 (-3785 3250);
PAINT SKYBLUE (-3785 3250);
FORCEPROP 1 LAST TOLERANCE 1%
J 0
(-3780 3450);
DISPLAY 0.617021 (-3780 3450);
PAINT SKYBLUE (-3780 3450);
FORCEPROP 1 LASTPIN (-3825 3325) $PN 2
J 0
(-3820 3335);
DISPLAY 0.617021 (-3820 3335);
PAINT ORANGE (-3820 3335);
FORCEPROP 1 LASTPIN (-3825 3525) $PN 1
J 0
(-3820 3487);
DISPLAY 0.617021 (-3820 3487);
PAINT ORANGE (-3820 3487);
FORCEPROP 1 LAST VALUE 10.0K
J 0
(-3780 3500);
DISPLAY 0.617021 (-3780 3500);
PAINT SKYBLUE (-3780 3500);
FORCEPROP 1 LAST LOCATION R8E30
J 0
(-3780 3550);
DISPLAY 0.617021 (-3780 3550);
PAINT AQUA (-3780 3550);
FORCEPROP 1 LAST MATERIAL CHIP
J 0
(-3785 3350);
DISPLAY 0.617021 (-3785 3350);
PAINT SKYBLUE (-3785 3350);
FORCEPROP 1 LAST WATTAGE 1/16W
J 0
(-3785 3400);
DISPLAY 0.617021 (-3785 3400);
PAINT SKYBLUE (-3785 3400);
FORCEPROP 1 LAST PART_NUMBER G21796-016
J 0
(-3785 3300);
DISPLAY 0.617021 (-3785 3300);
PAINT BLUE (-3785 3300);
FORCEPROP 2 LAST CDS_LIB mstr_discrete
J 0
(-3825 3425);
PAINT ORANGE (-3825 3425);
DISPLAY INVISIBLE (-3825 3425);
FORCEPROP 2 LAST CDS_LOCATION R8E30
J 0
(-3780 3550);
DISPLAY 0.617021 (-3780 3550);
PAINT AQUA (-3780 3550);
DISPLAY INVISIBLE (-3780 3550);
FORCEPROP 0 LAST ROOM PCIE_WAKE_BUFFER
J 0
(-3775 3650);
DISPLAY 1.021277 (-3775 3650);
PAINT ORANGE (-3775 3650);
DISPLAY INVISIBLE (-3775 3650);
FORCEPROP 1 LAST PATH I23
J 0
(-3775 3600);
DISPLAY 0.978723 (-3775 3600);
PAINT WHITE (-3775 3600);
DISPLAY INVISIBLE (-3775 3600);
FORCEPROP 2 LAST SEC 1
J 0
(-3775 3650);
DISPLAY 0.680851 (-3775 3650);
PAINT MONO (-3775 3650);
DISPLAY INVISIBLE (-3775 3650);
FORCEPROP 2 LAST SEC_TYPE 0402
J 0
(-3775 3650);
DISPLAY 1.021277 (-3775 3650);
PAINT ORANGE (-3775 3650);
DISPLAY INVISIBLE (-3775 3650);
FORCEADD P3V3_STBY..1
(-3825 3750);
FORCEPROP 3 LASTPIN (-3825 3700) SIG_NAME P3V3_STBY\g
J 0
(-3815 3710);
DISPLAY 0.659574 (-3815 3710);
PAINT MONO (-3815 3710);
DISPLAY INVISIBLE (-3815 3710);
FORCEPROP 1 LAST VOLTAGE 3.3V
J 0
(-3870 3707);
DISPLAY 0.340426 (-3870 3707);
PAINT SKYBLUE (-3870 3707);
DISPLAY INVISIBLE (-3870 3707);
FORCEPROP 2 LAST CDS_LIB mstr_symbols
J 0
(-3825 3750);
PAINT ORANGE (-3825 3750);
DISPLAY INVISIBLE (-3825 3750);
FORCEPROP 1 LAST PATH I24
J 0
(-3780 3752);
DISPLAY 0.340426 (-3780 3752);
PAINT GREEN (-3780 3752);
DISPLAY INVISIBLE (-3780 3752);
FORCEPROP 1 LAST SIZE 1B
J 0
(-3780 3772);
DISPLAY 0.340426 (-3780 3772);
PAINT GREEN (-3780 3772);
DISPLAY INVISIBLE (-3780 3772);
FORCEPROP 1 LAST BODY_TYPE PLUMBING
J 0
(-3870 3707);
DISPLAY 0.340426 (-3870 3707);
PAINT GREEN (-3870 3707);
DISPLAY INVISIBLE (-3870 3707);
FORCEPROP 1 LAST HDL_POWER P3V3_STBY
J 0
(-4125 3625);
DISPLAY 0.872340 (-4125 3625);
PAINT ORANGE (-4125 3625);
DISPLAY INVISIBLE (-4125 3625);
FORCEADD RES..2
(-4650 3425);
FORCEPROP 1 LASTPIN (-4650 3525) $PN 1
J 0
(-4645 3487);
DISPLAY 0.617021 (-4645 3487);
PAINT ORANGE (-4645 3487);
FORCEPROP 1 LASTPIN (-4650 3325) $PN 2
J 0
(-4645 3335);
DISPLAY 0.617021 (-4645 3335);
PAINT ORANGE (-4645 3335);
FORCEPROP 1 LAST PART_NUMBER G21796-016
J 0
(-4610 3300);
DISPLAY 0.617021 (-4610 3300);
PAINT BLUE (-4610 3300);
FORCEPROP 1 LAST PACK_TYPE 0402
J 0
(-4610 3250);
DISPLAY 0.617021 (-4610 3250);
PAINT SKYBLUE (-4610 3250);
FORCEPROP 1 LAST MATERIAL CHIP
J 0
(-4610 3350);
DISPLAY 0.617021 (-4610 3350);
PAINT SKYBLUE (-4610 3350);
FORCEPROP 1 LAST WATTAGE 1/16W
J 0
(-4610 3400);
DISPLAY 0.617021 (-4610 3400);
PAINT SKYBLUE (-4610 3400);
FORCEPROP 1 LAST VALUE 10.0K
J 0
(-4605 3500);
DISPLAY 0.617021 (-4605 3500);
PAINT SKYBLUE (-4605 3500);
FORCEPROP 1 LAST LOCATION R8E36
J 0
(-4605 3550);
DISPLAY 0.617021 (-4605 3550);
PAINT AQUA (-4605 3550);
FORCEPROP 1 LAST TOLERANCE 1%
J 0
(-4605 3450);
DISPLAY 0.617021 (-4605 3450);
PAINT SKYBLUE (-4605 3450);
FORCEPROP 2 LAST CDS_LIB mstr_discrete
J 0
(-4650 3425);
PAINT ORANGE (-4650 3425);
DISPLAY INVISIBLE (-4650 3425);
FORCEPROP 2 LAST CDS_LOCATION R8E36
J 0
(-4605 3550);
DISPLAY 0.617021 (-4605 3550);
PAINT AQUA (-4605 3550);
DISPLAY INVISIBLE (-4605 3550);
FORCEPROP 2 LAST SEC_TYPE 0402
J 0
(-4600 3650);
DISPLAY 1.021277 (-4600 3650);
PAINT ORANGE (-4600 3650);
DISPLAY INVISIBLE (-4600 3650);
FORCEPROP 2 LAST SEC 1
J 0
(-4600 3650);
DISPLAY 0.680851 (-4600 3650);
PAINT MONO (-4600 3650);
DISPLAY INVISIBLE (-4600 3650);
FORCEPROP 1 LAST PATH I28
J 0
(-4600 3600);
DISPLAY 0.978723 (-4600 3600);
PAINT WHITE (-4600 3600);
DISPLAY INVISIBLE (-4600 3600);
FORCEPROP 0 LAST ROOM PCIE_WAKE_BUFFER
J 0
(-4600 3650);
DISPLAY 1.021277 (-4600 3650);
PAINT ORANGE (-4600 3650);
DISPLAY INVISIBLE (-4600 3650);
FORCEADD RES..1
(-3050 2700);
FORCEPROP 1 LAST WATTAGE 1/16W
J 2
(-3075 2550);
DISPLAY 0.617021 (-3075 2550);
PAINT SKYBLUE (-3075 2550);
FORCEPROP 1 LASTPIN (-3150 2700) $PN 1
J 0
(-3138 2712);
DISPLAY 0.617021 (-3138 2712);
PAINT ORANGE (-3138 2712);
FORCEPROP 1 LAST VALUE 4.75K
J 2
(-3075 2600);
DISPLAY 0.617021 (-3075 2600);
PAINT SKYBLUE (-3075 2600);
FORCEPROP 1 LAST LOCATION R8E23
J 0
(-3100 2750);
DISPLAY 0.617021 (-3100 2750);
PAINT AQUA (-3100 2750);
FORCEPROP 1 LAST PART_NUMBER G21796-072
J 0
(-3100 2800);
DISPLAY 0.617021 (-3100 2800);
PAINT BLUE (-3100 2800);
FORCEPROP 1 LAST PACK_TYPE 0402
J 0
(-2925 2550);
DISPLAY 0.617021 (-2925 2550);
PAINT SKYBLUE (-2925 2550);
FORCEPROP 1 LAST MATERIAL CHIP
J 0
(-3050 2550);
DISPLAY 0.617021 (-3050 2550);
PAINT SKYBLUE (-3050 2550);
FORCEPROP 1 LAST TOLERANCE 1%
J 0
(-3050 2600);
DISPLAY 0.617021 (-3050 2600);
PAINT SKYBLUE (-3050 2600);
FORCEPROP 1 LASTPIN (-2950 2700) $PN 2
J 0
(-2988 2712);
DISPLAY 0.617021 (-2988 2712);
PAINT ORANGE (-2988 2712);
FORCEPROP 2 LAST BOM_COST SB
J 0
(-3100 2900);
DISPLAY 1.021277 (-3100 2900);
PAINT ORANGE (-3100 2900);
DISPLAY INVISIBLE (-3100 2900);
FORCEPROP 2 LAST SEC 1
J 0
(-3100 2900);
PAINT MONO (-3100 2900);
DISPLAY INVISIBLE (-3100 2900);
FORCEPROP 1 LAST PATH I3
J 0
(-3100 2850);
DISPLAY 0.978723 (-3100 2850);
PAINT WHITE (-3100 2850);
DISPLAY INVISIBLE (-3100 2850);
FORCEPROP 2 LAST ROOM PCIE_WAKE_BUFFER
J 0
(-3100 2850);
DISPLAY 1.021277 (-3100 2850);
PAINT ORANGE (-3100 2850);
DISPLAY INVISIBLE (-3100 2850);
FORCEPROP 2 LAST SEC_TYPE 0402
J 0
(-3100 2900);
DISPLAY 1.021277 (-3100 2900);
PAINT ORANGE (-3100 2900);
DISPLAY INVISIBLE (-3100 2900);
FORCEPROP 2 LAST CDS_LOCATION R8E23
J 0
(-3100 2750);
DISPLAY 0.617021 (-3100 2750);
PAINT AQUA (-3100 2750);
DISPLAY INVISIBLE (-3100 2750);
FORCEPROP 2 LAST CDS_LIB mstr_discrete
J 0
(-3050 2700);
PAINT ORANGE (-3050 2700);
DISPLAY INVISIBLE (-3050 2700);
FORCEADD RES..1
(-4350 2275);
FORCEPROP 1 LAST VALUE 0.0
J 2
(-4375 2175);
DISPLAY 0.617021 (-4375 2175);
PAINT SKYBLUE (-4375 2175);
FORCEPROP 1 LAST PACK_TYPE 0402
J 0
(-4575 2175);
DISPLAY 0.617021 (-4575 2175);
PAINT SKYBLUE (-4575 2175);
FORCEPROP 1 LAST WATTAGE 1/16W
J 2
(-4375 2125);
DISPLAY 0.617021 (-4375 2125);
PAINT SKYBLUE (-4375 2125);
FORCEPROP 1 LASTPIN (-4450 2275) $PN 1
J 0
(-4438 2287);
DISPLAY 0.617021 (-4438 2287);
PAINT ORANGE (-4438 2287);
FORCEPROP 1 LAST LOCATION R8E26
J 0
(-4400 2325);
DISPLAY 0.617021 (-4400 2325);
PAINT AQUA (-4400 2325);
FORCEPROP 1 LAST PART_NUMBER G21497-005
J 0
(-4475 2075);
DISPLAY 0.617021 (-4475 2075);
PAINT BLUE (-4475 2075);
FORCEPROP 1 LAST TOLERANCE 5%
J 0
(-4350 2175);
DISPLAY 0.617021 (-4350 2175);
PAINT SKYBLUE (-4350 2175);
FORCEPROP 1 LAST MATERIAL CHIP
J 0
(-4350 2125);
DISPLAY 0.617021 (-4350 2125);
PAINT SKYBLUE (-4350 2125);
FORCEPROP 1 LASTPIN (-4250 2275) $PN 2
J 0
(-4288 2287);
DISPLAY 0.617021 (-4288 2287);
PAINT ORANGE (-4288 2287);
FORCEPROP 2 LAST SEC_TYPE 0402
J 0
(-4400 2475);
DISPLAY 1.021277 (-4400 2475);
PAINT ORANGE (-4400 2475);
DISPLAY INVISIBLE (-4400 2475);
FORCEPROP 2 LAST SEC 1
J 0
(-4400 2475);
DISPLAY 0.680851 (-4400 2475);
PAINT MONO (-4400 2475);
DISPLAY INVISIBLE (-4400 2475);
FORCEPROP 2 LAST CDS_LOCATION R8E26
J 0
(-4400 2325);
DISPLAY 0.617021 (-4400 2325);
PAINT AQUA (-4400 2325);
DISPLAY INVISIBLE (-4400 2325);
FORCEPROP 1 LAST PATH I30
J 0
(-4400 2425);
DISPLAY 0.978723 (-4400 2425);
PAINT WHITE (-4400 2425);
DISPLAY INVISIBLE (-4400 2425);
FORCEPROP 0 LAST ROOM PCIE_WAKE_BUFFER
J 0
(-4400 2425);
DISPLAY 1.021277 (-4400 2425);
PAINT ORANGE (-4400 2425);
DISPLAY INVISIBLE (-4400 2425);
FORCEPROP 2 LAST CDS_LIB mstr_discrete
J 0
(-4350 2275);
PAINT ORANGE (-4350 2275);
DISPLAY INVISIBLE (-4350 2275);
FORCEADD RES..1
(-4075 2475);
FORCEPROP 1 LASTPIN (-4175 2475) $PN 1
J 0
(-4163 2487);
DISPLAY 0.617021 (-4163 2487);
PAINT ORANGE (-4163 2487);
FORCEPROP 1 LAST WATTAGE 1/16W
J 2
(-4100 2325);
DISPLAY 0.617021 (-4100 2325);
PAINT SKYBLUE (-4100 2325);
FORCEPROP 1 LAST PACK_TYPE 0402
J 0
(-4300 2375);
DISPLAY 0.617021 (-4300 2375);
PAINT SKYBLUE (-4300 2375);
FORCEPROP 1 LAST VALUE 0.0
J 2
(-4100 2375);
DISPLAY 0.617021 (-4100 2375);
PAINT SKYBLUE (-4100 2375);
FORCEPROP 1 LAST LOCATION R8E28
J 0
(-4125 2525);
DISPLAY 0.617021 (-4125 2525);
PAINT AQUA (-4125 2525);
FORCEPROP 1 LAST PART_NUMBER G21497-005
J 0
(-4200 2275);
DISPLAY 0.617021 (-4200 2275);
PAINT BLUE (-4200 2275);
FORCEPROP 1 LASTPIN (-3975 2475) $PN 2
J 0
(-4013 2487);
DISPLAY 0.617021 (-4013 2487);
PAINT ORANGE (-4013 2487);
FORCEPROP 1 LAST MATERIAL CHIP
J 0
(-4075 2325);
DISPLAY 0.617021 (-4075 2325);
PAINT SKYBLUE (-4075 2325);
FORCEPROP 1 LAST TOLERANCE 5%
J 0
(-4075 2375);
DISPLAY 0.617021 (-4075 2375);
PAINT SKYBLUE (-4075 2375);
FORCEPROP 2 LAST CDS_LOCATION R8E28
J 0
(-4125 2525);
DISPLAY 0.617021 (-4125 2525);
PAINT AQUA (-4125 2525);
DISPLAY INVISIBLE (-4125 2525);
FORCEPROP 2 LAST SEC_TYPE 0402
J 0
(-4125 2675);
DISPLAY 1.021277 (-4125 2675);
PAINT ORANGE (-4125 2675);
DISPLAY INVISIBLE (-4125 2675);
FORCEPROP 2 LAST SEC 1
J 0
(-4125 2675);
DISPLAY 0.680851 (-4125 2675);
PAINT MONO (-4125 2675);
DISPLAY INVISIBLE (-4125 2675);
FORCEPROP 1 LAST PATH I31
J 0
(-4125 2625);
DISPLAY 0.978723 (-4125 2625);
PAINT WHITE (-4125 2625);
DISPLAY INVISIBLE (-4125 2625);
FORCEPROP 0 LAST ROOM PCIE_WAKE_BUFFER
J 0
(-4125 2625);
DISPLAY 1.021277 (-4125 2625);
PAINT ORANGE (-4125 2625);
DISPLAY INVISIBLE (-4125 2625);
FORCEPROP 2 LAST CDS_LIB mstr_discrete
J 0
(-4075 2475);
PAINT ORANGE (-4075 2475);
DISPLAY INVISIBLE (-4075 2475);
FORCEADD RES..1
(-4350 2675);
FORCEPROP 1 LAST WATTAGE 1/16W
J 2
(-4375 2525);
DISPLAY 0.617021 (-4375 2525);
PAINT SKYBLUE (-4375 2525);
FORCEPROP 1 LAST PART_NUMBER G21497-005
J 0
(-4475 2475);
DISPLAY 0.617021 (-4475 2475);
PAINT BLUE (-4475 2475);
FORCEPROP 1 LAST MATERIAL CHIP
J 0
(-4350 2525);
DISPLAY 0.617021 (-4350 2525);
PAINT SKYBLUE (-4350 2525);
FORCEPROP 1 LAST VALUE 0.0
J 2
(-4375 2575);
DISPLAY 0.617021 (-4375 2575);
PAINT SKYBLUE (-4375 2575);
FORCEPROP 1 LAST PACK_TYPE 0402
J 0
(-4575 2575);
DISPLAY 0.617021 (-4575 2575);
PAINT SKYBLUE (-4575 2575);
FORCEPROP 1 LASTPIN (-4450 2675) $PN 1
J 0
(-4438 2687);
DISPLAY 0.617021 (-4438 2687);
PAINT ORANGE (-4438 2687);
FORCEPROP 1 LAST LOCATION R8E27
J 0
(-4400 2725);
DISPLAY 0.617021 (-4400 2725);
PAINT AQUA (-4400 2725);
FORCEPROP 1 LAST TOLERANCE 5%
J 0
(-4350 2575);
DISPLAY 0.617021 (-4350 2575);
PAINT SKYBLUE (-4350 2575);
FORCEPROP 1 LASTPIN (-4250 2675) $PN 2
J 0
(-4288 2687);
DISPLAY 0.617021 (-4288 2687);
PAINT ORANGE (-4288 2687);
FORCEPROP 2 LAST SEC_TYPE 0402
J 0
(-4400 2875);
DISPLAY 1.021277 (-4400 2875);
PAINT ORANGE (-4400 2875);
DISPLAY INVISIBLE (-4400 2875);
FORCEPROP 2 LAST SEC 1
J 0
(-4400 2875);
DISPLAY 0.680851 (-4400 2875);
PAINT MONO (-4400 2875);
DISPLAY INVISIBLE (-4400 2875);
FORCEPROP 2 LAST CDS_LOCATION R8E27
J 0
(-4400 2725);
DISPLAY 0.617021 (-4400 2725);
PAINT AQUA (-4400 2725);
DISPLAY INVISIBLE (-4400 2725);
FORCEPROP 1 LAST PATH I32
J 0
(-4400 2825);
DISPLAY 0.978723 (-4400 2825);
PAINT WHITE (-4400 2825);
DISPLAY INVISIBLE (-4400 2825);
FORCEPROP 0 LAST ROOM PCIE_WAKE_BUFFER
J 0
(-4400 2825);
DISPLAY 1.021277 (-4400 2825);
PAINT ORANGE (-4400 2825);
DISPLAY INVISIBLE (-4400 2825);
FORCEPROP 2 LAST CDS_LIB mstr_discrete
J 0
(-4350 2675);
PAINT ORANGE (-4350 2675);
DISPLAY INVISIBLE (-4350 2675);
FORCEADD RES..1
(-4075 2900);
FORCEPROP 1 LAST WATTAGE 1/16W
J 2
(-4100 2750);
DISPLAY 0.617021 (-4100 2750);
PAINT SKYBLUE (-4100 2750);
FORCEPROP 1 LAST VALUE 0.0
J 2
(-4100 2800);
DISPLAY 0.617021 (-4100 2800);
PAINT SKYBLUE (-4100 2800);
FORCEPROP 1 LAST PACK_TYPE 0402
J 0
(-4300 2800);
DISPLAY 0.617021 (-4300 2800);
PAINT SKYBLUE (-4300 2800);
FORCEPROP 1 LASTPIN (-4175 2900) $PN 1
J 0
(-4163 2912);
DISPLAY 0.617021 (-4163 2912);
PAINT ORANGE (-4163 2912);
FORCEPROP 1 LAST LOCATION R8E21
J 0
(-4125 2950);
DISPLAY 0.617021 (-4125 2950);
PAINT AQUA (-4125 2950);
FORCEPROP 1 LAST PART_NUMBER G21497-005
J 0
(-4200 2700);
DISPLAY 0.617021 (-4200 2700);
PAINT BLUE (-4200 2700);
FORCEPROP 1 LASTPIN (-3975 2900) $PN 2
J 0
(-4013 2912);
DISPLAY 0.617021 (-4013 2912);
PAINT ORANGE (-4013 2912);
FORCEPROP 1 LAST MATERIAL CHIP
J 0
(-4075 2750);
DISPLAY 0.617021 (-4075 2750);
PAINT SKYBLUE (-4075 2750);
FORCEPROP 1 LAST TOLERANCE 5%
J 0
(-4075 2800);
DISPLAY 0.617021 (-4075 2800);
PAINT SKYBLUE (-4075 2800);
FORCEPROP 2 LAST CDS_LOCATION R8E21
J 0
(-4125 2950);
DISPLAY 0.617021 (-4125 2950);
PAINT AQUA (-4125 2950);
DISPLAY INVISIBLE (-4125 2950);
FORCEPROP 1 LAST PATH I33
J 0
(-4125 3050);
DISPLAY 0.978723 (-4125 3050);
PAINT WHITE (-4125 3050);
DISPLAY INVISIBLE (-4125 3050);
FORCEPROP 0 LAST ROOM PCIE_WAKE_BUFFER
J 0
(-4125 3050);
DISPLAY 1.021277 (-4125 3050);
PAINT ORANGE (-4125 3050);
DISPLAY INVISIBLE (-4125 3050);
FORCEPROP 2 LAST SEC_TYPE 0402
J 0
(-4125 3100);
DISPLAY 1.021277 (-4125 3100);
PAINT ORANGE (-4125 3100);
DISPLAY INVISIBLE (-4125 3100);
FORCEPROP 2 LAST SEC 1
J 0
(-4125 3100);
DISPLAY 0.680851 (-4125 3100);
PAINT MONO (-4125 3100);
DISPLAY INVISIBLE (-4125 3100);
FORCEPROP 2 LAST CDS_LIB mstr_discrete
J 0
(-4075 2900);
PAINT ORANGE (-4075 2900);
DISPLAY INVISIBLE (-4075 2900);
FORCEADD P3V3_STBY..1
(-2525 2950);
FORCEPROP 3 LASTPIN (-2525 2900) SIG_NAME P3V3_STBY\g
J 0
(-2515 2910);
DISPLAY 0.659574 (-2515 2910);
PAINT MONO (-2515 2910);
DISPLAY INVISIBLE (-2515 2910);
FORCEPROP 1 LAST VOLTAGE 3.3V
J 0
(-2570 2907);
DISPLAY 0.340426 (-2570 2907);
PAINT SKYBLUE (-2570 2907);
DISPLAY INVISIBLE (-2570 2907);
FORCEPROP 2 LAST CDS_LIB mstr_symbols
J 0
(-2525 2950);
PAINT ORANGE (-2525 2950);
DISPLAY INVISIBLE (-2525 2950);
FORCEPROP 1 LAST SIZE 1B
J 0
(-2480 2972);
DISPLAY 0.340426 (-2480 2972);
PAINT GREEN (-2480 2972);
DISPLAY INVISIBLE (-2480 2972);
FORCEPROP 1 LAST PATH I4
J 0
(-2480 2952);
DISPLAY 0.340426 (-2480 2952);
PAINT GREEN (-2480 2952);
DISPLAY INVISIBLE (-2480 2952);
FORCEPROP 1 LAST BODY_TYPE PLUMBING
J 0
(-2570 2907);
DISPLAY 0.340426 (-2570 2907);
PAINT GREEN (-2570 2907);
DISPLAY INVISIBLE (-2570 2907);
FORCEPROP 1 LAST HDL_POWER P3V3_STBY
J 0
(-2825 2825);
DISPLAY 0.872340 (-2825 2825);
PAINT ORANGE (-2825 2825);
DISPLAY INVISIBLE (-2825 2825);
FORCEADD OFFPAGE..2
(-1675 2275);
FORCEPROP 2 LAST $XR0 118 
J 0
(-1486 2275);
DISPLAY 0.638298 (-1486 2275);
PAINT MONO (-1486 2275);
FORCEPROP 2 LAST CDS_LIB mstr_standard
J 0
(-1675 2275);
PAINT ORANGE (-1675 2275);
DISPLAY INVISIBLE (-1675 2275);
FORCEPROP 2 LAST PATH I5
J 0
(-1625 2350);
DISPLAY 1.021277 (-1625 2350);
PAINT ORANGE (-1625 2350);
DISPLAY INVISIBLE (-1625 2350);
FORCEPROP 1 LAST OFFPAGE TRUE
J 0
(-1350 2150);
DISPLAY 0.872340 (-1350 2150);
PAINT GREEN (-1350 2150);
DISPLAY INVISIBLE (-1350 2150);
FORCEPROP 1 LAST COMMENT_BODY TRUE
J 0
(-1720 2180);
DISPLAY 0.872340 (-1720 2180);
PAINT GREEN (-1720 2180);
DISPLAY INVISIBLE (-1720 2180);
FORCEADD INTEL_CORP_BPAGE..1
(0 0);
FORCEPROP 1 LAST CDS_CON_LAST_MODIFIED Tue Dec 01 11:52:03 2015
J 0
(-1425 325);
DISPLAY 0.659574 (-1425 325);
PAINT GREEN (-1425 325);
DISPLAY INVISIBLE (-1425 325);
FORCEPROP 1 LAST CUSTOM_TXT_CDS <CURRENT_DESIGN_SHEET> OF <TOTAL_DESIGN_SHEETS>
J 0
(-500 25);
PAINT GREEN (-500 25);
FORCEPROP 1 LAST CUSTOM_TXT_CDS <CON_LAST_MODIFIED>
J 0
(-1925 350);
PAINT GREEN (-1925 350);
FORCEPROP 2 LAST CUSTOM_TXT_CDS <XR_PAGE_TITLE>
J 0
(-7890 5250);
DISPLAY 0.638298 (-7890 5250);
PAINT PINK (-7890 5250);
DISPLAY INVISIBLE (-7890 5250);
FORCEPROP 1 LAST SCH_TITLE PCIE WAKE TRI-STATE BUFFER
J 0
(-7950 50);
DISPLAY 1.212766 (-7950 50);
PAINT GREEN (-7950 50);
FORCEPROP 1 LAST SCH_ADDRESS3 Santa Clara, CA 95052-8119
J 0
(-3975 25);
DISPLAY 0.617021 (-3975 25);
PAINT GREEN (-3975 25);
FORCEPROP 1 LAST SCH_ADDRESS2 P.O. BOX 58119
J 0
(-3975 75);
DISPLAY 0.617021 (-3975 75);
PAINT GREEN (-3975 75);
FORCEPROP 1 LAST SCH_ADDRESS1 2200 Mission College Blvd.
J 0
(-3975 125);
DISPLAY 0.617021 (-3975 125);
PAINT GREEN (-3975 125);
FORCEPROP 1 LAST SCH_REV 2.420
J 0
(-250 150);
DISPLAY 0.978723 (-250 150);
PAINT YELLOW (-250 150);
FORCEPROP 1 LAST SCH_DEPT BESD
J 1
(-4450 100);
DISPLAY 1.212766 (-4450 100);
PAINT YELLOW (-4450 100);
FORCEPROP 1 LAST SCH_NUMBER H4694802
J 0
(-1300 150);
DISPLAY 1.212766 (-1300 150);
PAINT YELLOW (-1300 150);
FORCEPROP 2 LAST PAGE_BORDER TRUE
J 0
(-7890 5250);
DISPLAY 0.425532 (-7890 5250);
PAINT PINK (-7890 5250);
DISPLAY INVISIBLE (-7890 5250);
FORCEPROP 2 LAST CDS_LIB mstr_symbols
J 0
(0 0);
DISPLAY 0.489362 (0 0);
PAINT ORANGE (0 0);
DISPLAY INVISIBLE (0 0);
FORCEPROP 1 LAST COMMENT_BODY TRUE
J 0
(12 12);
DISPLAY 0.319149 (12 12);
PAINT GREEN (12 12);
DISPLAY INVISIBLE (12 12);
FORCEPROP 2 LAST CDS_XR_PAGE_TITLE CR-142 : @BASEBOARD_FAB2_LIB.BASEBOARD_FAB2(SCH_1):PAGE142
J 0
(-7890 5250);
DISPLAY 0.638298 (-7890 5250);
PAINT PINK (-7890 5250);
DISPLAY INVISIBLE (-7890 5250);
FORCEADD DESIGN_NOTE..1
(-2925 1600);
FORCEPROP 0 LAST L1 PLACE CAP CLOSE TO TRI STATE BUFFER
J 0
(-3100 1450);
DISPLAY 1.021277 (-3100 1450);
PAINT ORANGE (-3100 1450);
FORCEPROP 2 LAST CDS_LIB mstr_symbols
J 0
(-2925 1600);
PAINT ORANGE (-2925 1600);
DISPLAY INVISIBLE (-2925 1600);
FORCEPROP 1 LAST COMMENT_BODY TRUE
J 0
(-2900 1700);
DISPLAY 0.978723 (-2900 1700);
PAINT ORANGE (-2900 1700);
DISPLAY INVISIBLE (-2900 1700);
FORCEADD CAD_NOTE..1
(-4525 4250);
FORCEPROP 0 LAST L1 ADD PULLUP NEAR X24 CONN
J 0
(-4675 4125);
DISPLAY 1.021277 (-4675 4125);
PAINT ORANGE (-4675 4125);
FORCEPROP 2 LAST CDS_LIB mstr_symbols
J 0
(-4525 4250);
PAINT ORANGE (-4525 4250);
DISPLAY INVISIBLE (-4525 4250);
FORCEPROP 1 LAST COMMENT_BODY TRUE
J 0
(-4500 4350);
DISPLAY 0.978723 (-4500 4350);
PAINT ORANGE (-4500 4350);
DISPLAY INVISIBLE (-4500 4350);
FORCEADD DNS..2
(-4295 3120);
PAINT RED (-4295 3120);
FORCEPROP 2 LAST CDS_LIB mstr_misc
J 0
(-4295 3120);
PAINT ORANGE (-4295 3120);
DISPLAY INVISIBLE (-4295 3120);
FORCEPROP 1 LAST COMMENT_BODY TRUE
R 1
J 0
(-4220 2895);
DISPLAY 0.872340 (-4220 2895);
PAINT GREEN (-4220 2895);
DISPLAY INVISIBLE (-4220 2895);
WIRE 16 -1 (-3500 1650)(-3500 1725);
WIRE 16 -1 (-3500 1300)(-3500 1450);
WIRE 16 -1 (-4650 3525)(-4650 3625);
WIRE 16 -1 (-4650 3625)(-3825 3625);
WIRE 16 -1 (-3825 3700)(-3825 3625);
WIRE 16 -1 (-3825 3625)(-3825 3525);
WIRE 16 -1 (-2950 2700)(-2525 2700);
WIRE 16 -1 (-2525 2700)(-2525 2900);
WIRE 16 -1 (-4450 2275)(-5350 2275);
FORCEPROP 2 LAST SIG_NAME FM_PE_OCP_WAKE_N
J 0
(-5350 2285);
DISPLAY 0.617021 (-5350 2285);
PAINT ORANGE (-5350 2285);
WIRE 16 -1 (-4450 2675)(-5350 2675);
FORCEPROP 2 LAST SIG_NAME FM_PE_M2_WAKE_N
J 0
(-5350 2685);
DISPLAY 0.617021 (-5350 2685);
PAINT ORANGE (-5350 2685);
WIRE 16 -1 (-5350 3125)(-4400 3125);
FORCEPROP 2 LAST SIG_NAME FM_PE_BMC_WAKE_N
J 0
(-5350 3135);
DISPLAY 0.617021 (-5350 3135);
PAINT ORANGE (-5350 3135);
WIRE 16 -1 (-5350 2900)(-4175 2900);
FORCEPROP 2 LAST SIG_NAME FM_PE_SPRV_WAKE_N
J 0
(-5350 2910);
DISPLAY 0.617021 (-5350 2910);
PAINT ORANGE (-5350 2910);
WIRE 16 -1 (-4175 2475)(-4650 2475);
WIRE 16 -1 (-4650 3325)(-4650 2475);
WIRE 16 -1 (-5350 2475)(-4650 2475);
FORCEPROP 2 LAST SIG_NAME FM_PE_SLOTX24_WAKE_N
J 0
(-5350 2485);
DISPLAY 0.617021 (-5350 2485);
PAINT ORANGE (-5350 2485);
WIRE 16 -1 (-3525 2700)(-3150 2700);
FORCEPROP 2 LAST SIG_NAME PU_TRI_STATE_EN
J 0
(-3510 2710);
DISPLAY 0.617021 (-3510 2710);
PAINT ORANGE (-3510 2710);
FORCEPROP 2 LASTPROP $XRERR UNIQUE?
J 0
(-3750 2710);
DISPLAY 0.638298 (-3750 2710);
PAINT MONO (-3750 2710);
DISPLAY INVISIBLE (-3750 2710);
WIRE 16 -1 (-3525 2375)(-3525 2700);
WIRE 16 -1 (-3825 3325)(-3825 3125);
WIRE 16 -1 (-3825 2900)(-3825 3125);
FORCEPROP 2 LAST SIG_NAME FM_ALL_WAKE_N
J 0
(-4160 3135);
DISPLAY 0.617021 (-4160 3135);
PAINT ORANGE (-4160 3135);
FORCEPROP 2 LASTPROP $XRERR UNIQUE?
J 0
(-4400 3135);
DISPLAY 0.638298 (-4400 3135);
PAINT MONO (-4400 3135);
DISPLAY INVISIBLE (-4400 3135);
WIRE 16 -1 (-4200 3125)(-3825 3125);
WIRE 16 -1 (-3825 2675)(-3825 2900);
WIRE 16 -1 (-3975 2900)(-3825 2900);
WIRE 16 -1 (-3825 2675)(-3825 2475);
WIRE 16 -1 (-3825 2675)(-4250 2675);
WIRE 16 -1 (-3825 2475)(-3825 2275);
WIRE 16 -1 (-3825 2475)(-3975 2475);
WIRE 16 -1 (-3825 2275)(-3675 2275);
WIRE 16 -1 (-4250 2275)(-3825 2275);
WIRE 16 -1 (-3375 2275)(-2725 2275);
FORCEPROP 2 LAST SIG_NAME IRQ_LVC3_WAKE_R_N
J 0
(-3185 2285);
DISPLAY 0.617021 (-3185 2285);
PAINT ORANGE (-3185 2285);
FORCEPROP 2 LASTPROP $XRERR UNIQUE?
J 0
(-3425 2285);
DISPLAY 0.638298 (-3425 2285);
PAINT MONO (-3425 2285);
DISPLAY INVISIBLE (-3425 2285);
WIRE 16 -1 (-2525 2275)(-1725 2275);
FORCEPROP 2 LAST SIG_NAME IRQ_LVC3_WAKE_N
J 0
(-2185 2285);
DISPLAY 0.617021 (-2185 2285);
PAINT ORANGE (-2185 2285);
WIRE 16 2175 (-4425 3200)(-4425 4025);
WIRE 16 2175 (-4700 3200)(-4425 3200);
WIRE 16 2175 (-4425 4025)(-3625 4025);
WIRE 16 2175 (-3625 4025)(-3625 4350);
WIRE 16 2175 (-4700 4350)(-4700 3200);
WIRE 16 2175 (-3625 4350)(-4700 4350);
DOT 1 (-4650 2475);
DOT 1 (-3825 2275);
DOT 1 (-3825 2475);
DOT 1 (-3825 2900);
DOT 1 (-3825 2675);
DOT 1 (-3825 3125);
DOT 1 (-3825 3625);
QUIT
